# T6G (Grand Teton) — schematic netlist excerpt (pin names and nets, part order shuffled) for the footprints in the layout excerpt that follows; sources: Cadence DE-HDL packaged netlist, KiCad conversion of 04192023_DAF0TMB3IC0_F0TG_MB_C_brd_V02_OCP.brd

J33  SCONN288_DDR506112002KQ  IO  pkg DDR288S_1-1VXC  page 103
  VIN_BULK0  = P12V_MEM_CPU1
  RFU0  = NC
  VIN_MGMT  = P3V3_AUX
  HSCL  = I3C_SPD_DDRF_CPU1_SCL
  HSDA  = I3C_SPD_DDRF_CPU1_SDA
  VSS0  = GND
  DQ0_A  = M_F_CPU1_SA_DQ<0>
  VSS1  = GND
  DQ1_A  = M_F_CPU1_SA_DQ<1>
  VSS2  = GND
  DQS0_A_T  = M_F_CPU1_SA_DQS_DP<0>
  DQS0_A_C  = M_F_CPU1_SA_DQS_DN<0>
  VSS3  = GND
  DQ4_A  = M_F_CPU1_SA_DQ<4>
  VSS4  = GND
  DQ5_A  = M_F_CPU1_SA_DQ<5>
  VSS5  = GND
  DQ8_A  = M_F_CPU1_SA_DQ<8>
  VSS6  = GND
  DQ9_A  = M_F_CPU1_SA_DQ<9>
  VSS7  = GND
  DQS1_A_T  = M_F_CPU1_SA_DQS_DP<1>
  DQS1_A_C  = M_F_CPU1_SA_DQS_DN<1>
  VSS8  = GND
  DQ12_A  = M_F_CPU1_SA_DQ<12>
  VSS9  = GND
  DQ13_A  = M_F_CPU1_SA_DQ<13>
  VSS10  = GND
  DQ16_A  = M_F_CPU1_SA_DQ<16>
  VSS11  = GND
  DQ17_A  = M_F_CPU1_SA_DQ<17>
  VSS12  = GND
  DQS2_A_T  = M_F_CPU1_SA_DQS_DP<2>
  DQS2_A_C  = M_F_CPU1_SA_DQS_DN<2>
  VSS13  = GND
  DQ20_A  = M_F_CPU1_SA_DQ<20>
  VSS14  = GND
  DQ21_A  = M_F_CPU1_SA_DQ<21>
  VSS15  = GND
  DQ24_A  = M_F_CPU1_SA_DQ<24>
  VSS16  = GND
  DQ25_A  = M_F_CPU1_SA_DQ<25>
  VSS17  = GND
  DQS3_A_T  = M_F_CPU1_SA_DQS_DP<3>
  DQS3_A_C  = M_F_CPU1_SA_DQS_DN<3>
  VSS18  = GND
  DQ28_A  = M_F_CPU1_SA_DQ<28>
  VSS19  = GND
  DQ29_A  = M_F_CPU1_SA_DQ<29>
  VSS20  = GND
  CB0_A  = M_F_CPU1_SA_CB<0>
  VSS21  = GND
  CB1_A  = M_F_CPU1_SA_CB<1>
  VSS22  = GND
  DQS4_A_T  = M_F_CPU1_SA_DQS_DP<4>
  DQS4_A_C  = M_F_CPU1_SA_DQS_DN<4>
  VSS23  = GND
  CB4_A  = M_F_CPU1_SA_CB<4>
  VSS24  = GND
  CB5_A  = M_F_CPU1_SA_CB<5>
  VSS25  = GND
  ALERT_N  = M_F_CPU1_ALERT_N
  VSS26  = GND
  CS0_A_N  = M_F_CPU1_SA_CS_N<0>
  VSS27  = GND
  CA0_A  = M_F_CPU1_SA_CA<0>
  VSS28  = GND
  CA2_A  = M_F_CPU1_SA_CA<2>
  VSS29  = GND
  CA4_A  = M_F_CPU1_SA_CA<4>
  VSS30  = GND
  CA6_A  = M_F_CPU1_SA_CA<6>
  VSS31  = GND
  PAR_A  = M_F_CPU1_SA_PAR
  VSS32  = GND
  CA0_B  = M_F_CPU1_SB_CA<0>
  VSS33  = GND
  CA2_B  = M_F_CPU1_SB_CA<2>
  VSS34  = GND
  CA4_B  = M_F_CPU1_SB_CA<4>
  VSS35  = GND
  CA6_B  = M_F_CPU1_SB_CA<6>
  VSS36  = GND
  CS0_B_N  = M_F_CPU1_SB_CS_N<0>
  VSS37  = GND
  \lbd||rsp_a_n\  = M_F_CPU1_SA_RSP<0>
  \lbs||rsp_b_n\  = M_F_CPU1_SB_RSP<0>
  VSS38  = GND
  CB4_B  = M_F_CPU1_SB_CB<4>
  VSS39  = GND
  CB5_B  = M_F_CPU1_SB_CB<5>
  VSS40  = GND
  \dqs9_b_t||tdqs9_b_t||dbi4_b_n\  = M_F_CPU1_SB_DQS_DP<9>
  \dqs9_b_c||tdqs9_b_c\  = M_F_CPU1_SB_DQS_DN<9>
  VSS41  = GND
  CB0_B  = M_F_CPU1_SB_CB<0>
  VSS42  = GND
  CB1_B  = M_F_CPU1_SB_CB<1>
  VSS43  = GND
  DQ0_B  = M_F_CPU1_SB_DQ<0>
  VSS44  = GND
  DQ1_B  = M_F_CPU1_SB_DQ<1>
  VSS45  = GND
  DQS0_B_T  = M_F_CPU1_SB_DQS_DP<0>
  DQS0_B_C  = M_F_CPU1_SB_DQS_DN<0>
  VSS46  = GND
  DQ4_B  = M_F_CPU1_SB_DQ<4>
  VSS47  = GND
  DQ5_B  = M_F_CPU1_SB_DQ<5>
  VSS48  = GND
  DQ8_B  = M_F_CPU1_SB_DQ<8>
  VSS49  = GND
  DQ9_B  = M_F_CPU1_SB_DQ<9>
  VSS50  = GND
  DQS1_B_T  = M_F_CPU1_SB_DQS_DP<1>
  DQS1_B_C  = M_F_CPU1_SB_DQS_DN<1>
  VSS51  = GND
  DQ12_B  = M_F_CPU1_SB_DQ<12>
  VSS52  = GND
  DQ13_B  = M_F_CPU1_SB_DQ<13>
  VSS53  = GND
  DQ16_B  = M_F_CPU1_SB_DQ<16>
  VSS54  = GND
  DQ17_B  = M_F_CPU1_SB_DQ<17>
  VSS55  = GND
  DQS2_B_T  = M_F_CPU1_SB_DQS_DP<2>
  DQS2_B_C  = M_F_CPU1_SB_DQS_DN<2>
  VSS56  = GND
  DQ20_B  = M_F_CPU1_SB_DQ<20>
  VSS57  = GND
  DQ21_B  = M_F_CPU1_SB_DQ<21>
  VSS58  = GND
  DQ24_B  = M_F_CPU1_SB_DQ<24>
  VSS59  = GND
  DQ25_B  = M_F_CPU1_SB_DQ<25>
  VSS60  = GND
  DQS3_B_T  = M_F_CPU1_SB_DQS_DP<3>
  DQS3_B_C  = M_F_CPU1_SB_DQS_DN<3>
  VSS61  = GND
  DQ28_B  = M_F_CPU1_SB_DQ<28>
  VSS62  = GND
  DQ29_B  = M_F_CPU1_SB_DQ<29>
  VSS63  = GND
  RFU1  = NC
  VIN_BULK1  = P12V_MEM_CPU1
  VIN_BULK2  = P12V_MEM_CPU1
  \pwr_good||fail_n\  = PWRGD_CHF_CPU1_DIMM
  HAS  = PD_CHF_CPU1_DIMM_SAA
  RFU2  = NC
  RFU3  = NC
  VSS64  = GND
  DQ2_A  = M_F_CPU1_SA_DQ<2>
  VSS65  = GND
  DQ3_A  = M_F_CPU1_SA_DQ<3>
  VSS66  = GND
  \dqs5_a_c||tdqs5_a_c||dqs5_a_t||tdqs5_a_t\  = M_F_CPU1_SA_DQS_DN<5>
  \dqs5_a_t||tdqs5_a_t\  = M_F_CPU1_SA_DQS_DP<5>
  VSS67  = GND
  DQ6_A  = M_F_CPU1_SA_DQ<6>
  VSS68  = GND
  DQ7_A  = M_F_CPU1_SA_DQ<7>
  VSS69  = GND
  DQ10_A  = M_F_CPU1_SA_DQ<10>
  VSS70  = GND
  DQ11_A  = M_F_CPU1_SA_DQ<11>
  VSS71  = GND
  \dqs6_a_c||tdqs6_a_c||dqs6_a_t||tdqs6_a_t\  = M_F_CPU1_SA_DQS_DN<6>
  \dqs6_a_t||tdqs6_a_t\  = M_F_CPU1_SA_DQS_DP<6>
  VSS72  = GND
  DQ14_A  = M_F_CPU1_SA_DQ<14>
  VSS73  = GND
  DQ15_A  = M_F_CPU1_SA_DQ<15>
  VSS74  = GND
  DQ18_A  = M_F_CPU1_SA_DQ<18>
  VSS75  = GND
  DQ19_A  = M_F_CPU1_SA_DQ<19>
  VSS76  = GND
  \dqs7_a_c||tdqs7_a_c\  = M_F_CPU1_SA_DQS_DN<7>
  \dqs7_a_t||tdqs7_a_t\  = M_F_CPU1_SA_DQS_DP<7>
  VSS77  = GND
  DQ22_A  = M_F_CPU1_SA_DQ<22>
  VSS78  = GND
  DQ23_A  = M_F_CPU1_SA_DQ<23>
  VSS79  = GND
  DQ26_A  = M_F_CPU1_SA_DQ<26>
  VSS80  = GND
  DQ27_A  = M_F_CPU1_SA_DQ<27>
  VSS81  = GND
  \dqs8_a_c||tdqs8_a_c\  = M_F_CPU1_SA_DQS_DN<8>
  \dqs8_a_t||tdqs8_a_t\  = M_F_CPU1_SA_DQS_DP<8>
  VSS82  = GND
  DQ30_A  = M_F_CPU1_SA_DQ<30>
  VSS83  = GND
  DQ31_A  = M_F_CPU1_SA_DQ<31>
  VSS84  = GND
  CB2_A  = M_F_CPU1_SA_CB<2>
  VSS85  = GND
  CB3_A  = M_F_CPU1_SA_CB<3>
  VSS86  = GND
  \dqs9_a_c||tdqs9_a_c\  = M_F_CPU1_SA_DQS_DN<9>
  \dqs9_a_t||tdqs9_a_t\  = M_F_CPU1_SA_DQS_DP<9>
  VSS87  = GND
  CB6_A  = M_F_CPU1_SA_CB<6>
  VSS88  = GND
  CB7_A  = M_F_CPU1_SA_CB<7>
  VSS89  = GND
  RESET_N  = M_F_CPU1_RESET_N
  VSS90  = GND
  CS1_A_N  = M_F_CPU1_SA_CS_N<1>
  VSS91  = GND
  CA1_A  = M_F_CPU1_SA_CA<1>
  VSS92  = GND
  CA3_A  = M_F_CPU1_SA_CA<3>
  VSS93  = GND
  CA5_A  = M_F_CPU1_SA_CA<5>
  VSS94  = GND
  CK_T  = M_F_CPU1_CLK_DP<0>
  CK_C  = M_F_CPU1_CLK_DN<0>
  VSS95  = GND
  RFU4  = NC
  CA1_B  = M_F_CPU1_SB_CA<1>
  VSS96  = GND
  CA3_B  = M_F_CPU1_SB_CA<3>
  VSS97  = GND
  CA5_B  = M_F_CPU1_SB_CA<5>
  VSS98  = GND
  PAR_B  = M_F_CPU1_SB_PAR
  VSS99  = GND
  CS1_B_N  = M_F_CPU1_SB_CS_N<1>
  VSS100  = GND
  RFU5  = NC
  RFU6  = NC
  VSS101  = GND
  CB6_B  = M_F_CPU1_SB_CB<6>
  VSS102  = GND
  CB7_B  = M_F_CPU1_SB_CB<7>
  VSS103  = GND
  DQS4_B_C  = M_F_CPU1_SB_DQS_DN<4>
  DQS4_B_T  = M_F_CPU1_SB_DQS_DP<4>
  VSS104  = GND
  CB2_B  = M_F_CPU1_SB_CB<2>
  VSS105  = GND
  CB3_B  = M_F_CPU1_SB_CB<3>
  VSS106  = GND
  DQ2_B  = M_F_CPU1_SB_DQ<2>
  VSS107  = GND
  DQ3_B  = M_F_CPU1_SB_DQ<3>
  VSS108  = GND
  \dqs5_b_c||tdqs5_b_c\  = M_F_CPU1_SB_DQS_DN<5>
  \dqs5_b_t||tdqs5_b_t\  = M_F_CPU1_SB_DQS_DP<5>
  VSS109  = GND
  DQ6_B  = M_F_CPU1_SB_DQ<6>
  VSS110  = GND
  DQ7_B  = M_F_CPU1_SB_DQ<7>
  VSS111  = GND
  DQ10_B  = M_F_CPU1_SB_DQ<10>
  VSS112  = GND
  DQ11_B  = M_F_CPU1_SB_DQ<11>
  VSS113  = GND
  \dqs6_b_c||tdqs6_b_c\  = M_F_CPU1_SB_DQS_DN<6>
  \dqs6_b_t||tdqs6_b_t\  = M_F_CPU1_SB_DQS_DP<6>
  VSS114  = GND
  DQ14_B  = M_F_CPU1_SB_DQ<14>
  VSS115  = GND
  DQ15_B  = M_F_CPU1_SB_DQ<15>
  VSS116  = GND
  DQ18_B  = M_F_CPU1_SB_DQ<18>
  VSS117  = GND
  DQ19_B  = M_F_CPU1_SB_DQ<19>
  VSS118  = GND
  \dqs7_b_c||tdqs7_b_c\  = M_F_CPU1_SB_DQS_DN<7>
  \dqs7_b_t||tdqs7_b_t\  = M_F_CPU1_SB_DQS_DP<7>
  VSS119  = GND
  DQ22_B  = M_F_CPU1_SB_DQ<22>
  VSS120  = GND
  DQ23_B  = M_F_CPU1_SB_DQ<23>
  VSS121  = GND
  DQ26_B  = M_F_CPU1_SB_DQ<26>
  VSS122  = GND
  DQ27_B  = M_F_CPU1_SB_DQ<27>
  VSS123  = GND
  \dqs8_b_c||tdqs8_b_c\  = M_F_CPU1_SB_DQS_DN<8>
  \dqs8_b_t||tdqs8_b_t\  = M_F_CPU1_SB_DQS_DP<8>
  VSS124  = GND
  DQ30_B  = M_F_CPU1_SB_DQ<30>
  VSS125  = GND
  DQ31_B  = M_F_CPU1_SB_DQ<31>
  VSS126  = GND
  G1  = GND
  G2  = GND
  G3  = GND

(kicad_pcb
	(version 20260206)
	(generator "pcbnew")
	(generator_version "10.0")
	(general
		(thickness 1.6)
		(legacy_teardrops no)
	)
	(paper "A4")
	(title_block
		(title "04192023_DAF0TMB3IC0_F0TG_MB_C_brd_V02_OCP.brd")
		(comment 1 "Grand Teton / footprint 4248 of 8354 (J33), pads 277-291 of 291")
	)
	(layers
		(0 "F.Cu" signal "TOP")
		(4 "In1.Cu" signal "GND")
		(6 "In2.Cu" signal "IN1")
		(8 "In3.Cu" signal "GND1")
		(10 "In4.Cu" signal "IN2")
		(12 "In5.Cu" signal "GND2")
		(14 "In6.Cu" signal "IN3")
		(16 "In7.Cu" signal "GND3")
		(18 "In8.Cu" signal "VCC")
		(20 "In9.Cu" signal "VCC1")
		(22 "In10.Cu" signal "GND4")
		(24 "In11.Cu" signal "IN4")
		(26 "In12.Cu" signal "GND5")
		(28 "In13.Cu" signal "IN5")
		(30 "In14.Cu" signal "GND6")
		(32 "In15.Cu" signal "IN6")
		(34 "In16.Cu" signal "GND7")
		(2 "B.Cu" signal "BOTTOM")
		(9 "F.Adhes" user "F.Adhesive")
		(11 "B.Adhes" user "B.Adhesive")
		(13 "F.Paste" user "Package Geometry/Pastemask Top")
		(15 "B.Paste" user "Package Geometry/Pastemask Bottom")
		(5 "F.SilkS" user "Ref Des/Silkscreen Top")
		(7 "B.SilkS" user "Ref Des/Silkscreen Bottom")
		(1 "F.Mask" user "Board Geometry/Soldermask Top")
		(3 "B.Mask" user "Board Geometry/Soldermask Bottom")
		(17 "Dwgs.User" user "User.Drawings")
		(19 "Cmts.User" user "User.Comments")
		(21 "Eco1.User" user "User.Eco1")
		(23 "Eco2.User" user "User.Eco2")
		(25 "Edge.Cuts" user "Board Geometry/Outline")
		(27 "Margin" user)
		(31 "F.CrtYd" user "Package Geometry/Place Bound Top")
		(29 "B.CrtYd" user "Package Geometry/Place Bound Bottom")
		(35 "F.Fab" user "Ref Des/Assembly Top")
		(33 "B.Fab" user "Ref Des/Assembly Bottom")
	)
	(footprint ""
		(layer "F.Cu")
		(at 19.658076 -255.560322 180)
		(property "Reference" "J33"
			(at -1.25984 -82.079846 0)
			(unlocked yes)
			(layer "F.SilkS")
			(effects
				(font
					(size 0.7874 0.5842)
					(thickness 0.1524)
				)
			)
		)
		(property "Value" ""
			(at 0 0 180)
			(layer "F.Fab")
			(effects
				(font
					(size 1.27 1.27)
				)
			)
		)
		(duplicate_pad_numbers_are_jumpers no)
		(pad "277" smd rect
			(at 2.050034 53.975 90)
			(size 0.519938 1.4986)
			(layers "F.Cu" "F.Mask" "F.Paste")
			(net "GND")
		)
		(pad "278" smd rect
			(at 2.050034 54.824884 90)
			(size 0.519938 1.4986)
			(layers "F.Cu" "F.Mask" "F.Paste")
			(net "M_F_CPU1_SB_DQ<26>")
		)
		(pad "279" smd rect
			(at 2.050034 55.675022 90)
			(size 0.519938 1.4986)
			(layers "F.Cu" "F.Mask" "F.Paste")
			(net "GND")
		)
		(pad "280" smd rect
			(at 2.050034 56.524906 90)
			(size 0.519938 1.4986)
			(layers "F.Cu" "F.Mask" "F.Paste")
			(net "M_F_CPU1_SB_DQ<27>")
		)
		(pad "281" smd rect
			(at 2.050034 57.375044 90)
			(size 0.519938 1.4986)
			(layers "F.Cu" "F.Mask" "F.Paste")
			(net "GND")
		)
		(pad "282" smd rect
			(at 2.050034 58.224928 90)
			(size 0.519938 1.4986)
			(layers "F.Cu" "F.Mask" "F.Paste")
			(net "M_F_CPU1_SB_DQS_DN<8>")
		)
		(pad "283" smd rect
			(at 2.050034 59.075066 90)
			(size 0.519938 1.4986)
			(layers "F.Cu" "F.Mask" "F.Paste")
			(net "M_F_CPU1_SB_DQS_DP<8>")
		)
		(pad "284" smd rect
			(at 2.050034 59.92495 90)
			(size 0.519938 1.4986)
			(layers "F.Cu" "F.Mask" "F.Paste")
			(net "GND")
		)
		(pad "285" smd rect
			(at 2.050034 60.775088 90)
			(size 0.519938 1.4986)
			(layers "F.Cu" "F.Mask" "F.Paste")
			(net "M_F_CPU1_SB_DQ<30>")
		)
		(pad "286" smd rect
			(at 2.050034 61.624972 90)
			(size 0.519938 1.4986)
			(layers "F.Cu" "F.Mask" "F.Paste")
			(net "GND")
		)
		(pad "287" smd rect
			(at 2.050034 62.47511 90)
			(size 0.519938 1.4986)
			(layers "F.Cu" "F.Mask" "F.Paste")
			(net "M_F_CPU1_SB_DQ<31>")
		)
		(pad "288" smd rect
			(at 2.050034 63.324994 90)
			(size 0.519938 1.4986)
			(layers "F.Cu" "F.Mask" "F.Paste")
			(net "GND")
		)
		(pad "G1" thru_hole oval
			(at 0 -68.97497 90)
			(size 1.7272 3.4798)
			(drill oval 1.2192 2.4638)
			(layers "*.Cu" "*.Mask")
			(remove_unused_layers no)
			(net "GND")
			(clearance 0.127)
			(thermal_gap 0.127)
		)
		(pad "G2" thru_hole oval
			(at 0 3.875024 90)
			(size 1.7272 3.4798)
			(drill oval 1.2192 2.4638)
			(layers "*.Cu" "*.Mask")
			(remove_unused_layers no)
			(net "GND")
			(clearance 0.127)
			(thermal_gap 0.127)
		)
		(pad "G3" thru_hole oval
			(at 0 68.97497 90)
			(size 1.7272 3.4798)
			(drill oval 1.2192 2.4638)
			(layers "*.Cu" "*.Mask")
			(remove_unused_layers no)
			(net "GND")
			(clearance 0.127)
			(thermal_gap 0.127)
		)
	)
)
